(kicad_pcb
	(version 20260206)
	(generator "pcbnew")
	(generator_version "10.0")
	(general
		(thickness 1.6)
		(legacy_teardrops no)
	)
	(paper "A4")
	(title_block
		(title "peb — Lightning_PEB_BRD.brd")
		(comment 1 "Lightning (Wiwynn / Facebook NVMe JBOF) / footprints 400-407 of 2563")
	)
	(layers
		(0 "F.Cu" signal "TOP")
		(4 "In1.Cu" signal "L2GND")
		(6 "In2.Cu" signal "L3")
		(8 "In3.Cu" signal "L4VCC")
		(10 "In4.Cu" signal "L5VCC")
		(12 "In5.Cu" signal "L6")
		(14 "In6.Cu" signal "L7GND")
		(2 "B.Cu" signal "BOTTOM")
		(9 "F.Adhes" user "F.Adhesive")
		(11 "B.Adhes" user "B.Adhesive")
		(13 "F.Paste" user "Package Geometry/Pastemask Top")
		(15 "B.Paste" user "Package Geometry/Pastemask Bottom")
		(5 "F.SilkS" user "Ref Des/Silkscreen Top")
		(7 "B.SilkS" user "Ref Des/Silkscreen Bottom")
		(1 "F.Mask" user "Board Geometry/Soldermask Top")
		(3 "B.Mask" user "Board Geometry/Soldermask Bottom")
		(17 "Dwgs.User" user "User.Drawings")
		(19 "Cmts.User" user "User.Comments")
		(21 "Eco1.User" user "User.Eco1")
		(23 "Eco2.User" user "User.Eco2")
		(25 "Edge.Cuts" user "Board Geometry/Outline")
		(27 "Margin" user)
		(31 "F.CrtYd" user "Package Geometry/Place Bound Top")
		(29 "B.CrtYd" user "Package Geometry/Place Bound Bottom")
		(35 "F.Fab" user "Ref Des/Assembly Top")
		(33 "B.Fab" user "Ref Des/Assembly Bottom")
	)
	(footprint ""
		(layer "F.Cu")
		(at 14.986 -113.411 90)
		(property "Reference" "PG69"
			(at 0 0 90)
			(layer "F.SilkS")
			(hide yes)
			(effects
				(font
					(size 1.27 1.27)
				)
			)
		)
		(property "Value" "GAP-CLOSE-PWR-3-GP"
			(at 0.0254 -6.5786 90)
			(unlocked yes)
			(layer "F.Fab")
			(hide yes)
			(effects
				(font
					(size 1.016 1.016)
					(thickness 0.1524)
				)
			)
		)
		(property "Device Type" "GAP-CLOSE-PWR-3"
			(at 0.0254 -8.255 90)
			(unlocked yes)
			(layer "F.Fab")
			(hide yes)
			(effects
				(font
					(size 1.016 1.016)
					(thickness 0.1524)
				)
			)
		)
		(duplicate_pad_numbers_are_jumpers no)
		(fp_rect
			(start -0.7112 0.4572)
			(end 0.7112 -0.4572)
			(stroke
				(width 0)
				(type default)
			)
			(fill no)
			(layer "F.CrtYd")
		)
		(fp_poly
			(pts
				(xy -0.7112 -0.4572) (xy 0.7112 -0.4572) (xy 0.7112 0.4572) (xy -0.7112 0.4572)
			)
			(stroke
				(width 0)
				(type default)
			)
			(fill no)
			(layer "F.Fab")
		)
		(pad "1" smd rect
			(at -0.3048 0 90)
			(size 0.6604 0.762)
			(layers "F.Cu" "F.Mask" "F.Paste")
			(net "P1V26_PWR")
		)
		(pad "2" smd rect
			(at 0.3048 0 90)
			(size 0.6604 0.762)
			(layers "F.Cu" "F.Mask" "F.Paste")
			(net "P1V26_STBY")
		)
	)
	(footprint ""
		(layer "F.Cu")
		(at 57.99201 -212.420454 180)
		(property "Reference" "C359"
			(at 0 0 180)
			(layer "F.SilkS")
			(hide yes)
			(effects
				(font
					(size 1.27 1.27)
				)
			)
		)
		(property "Value" "SCD22U10V2KX-1GP"
			(at 1.1811 -2.7051 180)
			(unlocked yes)
			(layer "F.Fab")
			(hide yes)
			(effects
				(font
					(size 1.016 1.016)
					(thickness 0.1524)
				)
			)
		)
		(property "Device Type" "C402H22"
			(at 1.1811 -4.2291 180)
			(unlocked yes)
			(layer "F.Fab")
			(hide yes)
			(effects
				(font
					(size 1.016 1.016)
					(thickness 0.1524)
				)
			)
		)
		(duplicate_pad_numbers_are_jumpers no)
		(fp_rect
			(start -0.4318 0.9525)
			(end 0.4318 -0.9525)
			(stroke
				(width 0)
				(type default)
			)
			(fill no)
			(layer "F.CrtYd")
		)
		(fp_rect
			(start -0.4318 0.9525)
			(end 0.4318 -0.9525)
			(stroke
				(width 0)
				(type default)
			)
			(fill no)
			(layer "F.Fab")
		)
		(pad "1" smd custom
			(at 0 -0.4445 180)
			(size 0.1524 0.1524)
			(layers "F.Cu" "F.Mask" "F.Paste")
			(net "PCIE_TX_CAP_P72")
			(options
				(clearance outline)
				(anchor circle)
			)
			(primitives
				(gr_poly
					(pts
						(arc
							(start 0.3048 -0.2032)
							(mid 0.275042 -0.275042)
							(end 0.2032 -0.3048)
						)
						(arc
							(start -0.2032 -0.3048)
							(mid -0.275042 -0.275042)
							(end -0.3048 -0.2032)
						)
						(arc
							(start -0.3048 0.2032)
							(mid -0.275042 0.275042)
							(end -0.2032 0.3048)
						)
						(arc
							(start 0.2032 0.3048)
							(mid 0.275042 0.275042)
							(end 0.3048 0.2032)
						)
					)
					(width 0)
					(fill yes)
				)
			)
		)
		(pad "2" smd custom
			(at 0 0.4445 180)
			(size 0.1524 0.1524)
			(layers "F.Cu" "F.Mask" "F.Paste")
			(net "PCIE_TX_P72")
			(options
				(clearance outline)
				(anchor circle)
			)
			(primitives
				(gr_poly
					(pts
						(arc
							(start 0.3048 -0.2032)
							(mid 0.275042 -0.275042)
							(end 0.2032 -0.3048)
						)
						(arc
							(start -0.2032 -0.3048)
							(mid -0.275042 -0.275042)
							(end -0.3048 -0.2032)
						)
						(arc
							(start -0.3048 0.2032)
							(mid -0.275042 0.275042)
							(end -0.2032 0.3048)
						)
						(arc
							(start 0.2032 0.3048)
							(mid 0.275042 0.275042)
							(end 0.3048 0.2032)
						)
					)
					(width 0)
					(fill yes)
				)
			)
		)
	)
	(footprint ""
		(layer "F.Cu")
		(at 21.0312 -193.6496 90)
		(property "Reference" "C7275"
			(at 0 0 90)
			(layer "F.SilkS")
			(hide yes)
			(effects
				(font
					(size 1.27 1.27)
				)
			)
		)
		(property "Value" "SC1U16V3KX-5GP"
			(at 0 -2.8194 90)
			(unlocked yes)
			(layer "F.Fab")
			(hide yes)
			(effects
				(font
					(size 1.016 1.016)
					(thickness 0.1524)
				)
			)
		)
		(property "Device Type" "C603H36"
			(at 0 -4.3434 90)
			(unlocked yes)
			(layer "F.Fab")
			(hide yes)
			(effects
				(font
					(size 1.016 1.016)
					(thickness 0.1524)
				)
			)
		)
		(duplicate_pad_numbers_are_jumpers no)
		(fp_line
			(start 0.508 0)
			(end -0.508 0)
			(stroke
				(width 0.2032)
				(type default)
			)
			(layer "F.SilkS")
		)
		(fp_rect
			(start -0.5842 1.3335)
			(end 0.5842 -1.3335)
			(stroke
				(width 0)
				(type default)
			)
			(fill no)
			(layer "F.CrtYd")
		)
		(fp_rect
			(start -0.5842 1.3335)
			(end 0.5842 -1.3335)
			(stroke
				(width 0)
				(type default)
			)
			(fill no)
			(layer "F.Fab")
		)
		(pad "1" smd custom
			(at 0 -0.762 90)
			(size 0.2159 0.2159)
			(layers "F.Cu" "F.Mask" "F.Paste")
			(net "MB0_CM_OV_R")
			(options
				(clearance outline)
				(anchor circle)
			)
			(primitives
				(gr_poly
					(pts
						(arc
							(start -0.3302 -0.4318)
							(mid -0.402042 -0.402042)
							(end -0.4318 -0.3302)
						)
						(arc
							(start -0.4318 0.3302)
							(mid -0.402042 0.402042)
							(end -0.3302 0.4318)
						)
						(arc
							(start 0.3302 0.4318)
							(mid 0.402042 0.402042)
							(end 0.4318 0.3302)
						)
						(arc
							(start 0.4318 -0.3302)
							(mid 0.402042 -0.402042)
							(end 0.3302 -0.4318)
						)
					)
					(width 0)
					(fill yes)
				)
			)
		)
		(pad "2" smd custom
			(at 0 0.762 90)
			(size 0.2159 0.2159)
			(layers "F.Cu" "F.Mask" "F.Paste")
			(net "AGND_CURRENT_MON")
			(options
				(clearance outline)
				(anchor circle)
			)
			(primitives
				(gr_poly
					(pts
						(arc
							(start -0.3302 -0.4318)
							(mid -0.402042 -0.402042)
							(end -0.4318 -0.3302)
						)
						(arc
							(start -0.4318 0.3302)
							(mid -0.402042 0.402042)
							(end -0.3302 0.4318)
						)
						(arc
							(start 0.3302 0.4318)
							(mid 0.402042 0.402042)
							(end 0.4318 0.3302)
						)
						(arc
							(start 0.4318 -0.3302)
							(mid 0.402042 -0.402042)
							(end 0.3302 -0.4318)
						)
					)
					(width 0)
					(fill yes)
				)
			)
		)
	)
	(footprint ""
		(layer "F.Cu")
		(at 320.421 -99.568)
		(property "Reference" "R7914"
			(at 0 0 0)
			(layer "F.SilkS")
			(hide yes)
			(effects
				(font
					(size 1.27 1.27)
				)
			)
		)
		(property "Value" "330R2J-3-GP"
			(at 0.064008 -3.993896 0)
			(unlocked yes)
			(layer "F.Fab")
			(hide yes)
			(effects
				(font
					(size 1.016 1.016)
					(thickness 0.1524)
				)
			)
		)
		(property "Device Type" "R402H16"
			(at 0.064008 -5.517896 0)
			(unlocked yes)
			(layer "F.Fab")
			(hide yes)
			(effects
				(font
					(size 1.016 1.016)
					(thickness 0.1524)
				)
			)
		)
		(duplicate_pad_numbers_are_jumpers no)
		(fp_line
			(start -0.508 -0.9398)
			(end -0.508 0.9398)
			(stroke
				(width 0.1524)
				(type default)
			)
			(layer "F.SilkS")
		)
		(fp_line
			(start 0.508 -0.9398)
			(end -0.508 -0.9398)
			(stroke
				(width 0.1524)
				(type default)
			)
			(layer "F.SilkS")
		)
		(fp_rect
			(start -0.508 0.9398)
			(end 0.508 -0.9398)
			(stroke
				(width 0)
				(type default)
			)
			(fill no)
			(layer "F.CrtYd")
		)
		(fp_rect
			(start -0.508 0.9398)
			(end 0.508 -0.9398)
			(stroke
				(width 0)
				(type default)
			)
			(fill no)
			(layer "F.Fab")
		)
		(pad "1" smd custom
			(at 0 -0.4445)
			(size 0.1397 0.1397)
			(layers "F.Cu" "F.Mask" "F.Paste")
			(net "TWI_SDA3")
			(options
				(clearance outline)
				(anchor circle)
			)
			(primitives
				(gr_poly
					(pts
						(arc
							(start -0.1778 -0.2794)
							(mid -0.249642 -0.249642)
							(end -0.2794 -0.1778)
						)
						(arc
							(start -0.2794 0.1778)
							(mid -0.249642 0.249642)
							(end -0.1778 0.2794)
						)
						(arc
							(start 0.1778 0.2794)
							(mid 0.249642 0.249642)
							(end 0.2794 0.1778)
						)
						(arc
							(start 0.2794 -0.1778)
							(mid 0.249642 -0.249642)
							(end 0.1778 -0.2794)
						)
					)
					(width 0)
					(fill yes)
				)
			)
		)
		(pad "2" smd custom
			(at 0 0.4445)
			(size 0.1397 0.1397)
			(layers "F.Cu" "F.Mask" "F.Paste")
			(net "IOEXP_TWI_SDA3")
			(options
				(clearance outline)
				(anchor circle)
			)
			(primitives
				(gr_poly
					(pts
						(arc
							(start -0.1778 -0.2794)
							(mid -0.249642 -0.249642)
							(end -0.2794 -0.1778)
						)
						(arc
							(start -0.2794 0.1778)
							(mid -0.249642 0.249642)
							(end -0.1778 0.2794)
						)
						(arc
							(start 0.1778 0.2794)
							(mid 0.249642 0.249642)
							(end 0.2794 0.1778)
						)
						(arc
							(start 0.2794 -0.1778)
							(mid 0.249642 -0.249642)
							(end 0.1778 -0.2794)
						)
					)
					(width 0)
					(fill yes)
				)
			)
		)
	)
	(footprint ""
		(layer "F.Cu")
		(at 288.544 -57.15 180)
		(property "Reference" "Q38"
			(at 0 0 180)
			(layer "F.SilkS")
			(hide yes)
			(effects
				(font
					(size 1.27 1.27)
				)
			)
		)
		(property "Value" "2N7002K-1-GP"
			(at 0.127 -8.9662 180)
			(unlocked yes)
			(layer "F.Fab")
			(hide yes)
			(effects
				(font
					(size 1.016 1.016)
					(thickness 0.1524)
				)
			)
		)
		(property "Device Type" "SOT23DGS2D4H44"
			(at 0.127 -10.4902 180)
			(unlocked yes)
			(layer "F.Fab")
			(hide yes)
			(effects
				(font
					(size 1.016 1.016)
					(thickness 0.1524)
				)
			)
		)
		(duplicate_pad_numbers_are_jumpers no)
		(fp_line
			(start 1.651 1.778)
			(end 1.651 -1.778)
			(stroke
				(width 0.1524)
				(type default)
			)
			(layer "F.SilkS")
		)
		(fp_line
			(start 1.651 -1.778)
			(end -1.651 -1.778)
			(stroke
				(width 0.1524)
				(type default)
			)
			(layer "F.SilkS")
		)
		(fp_line
			(start -1.651 1.778)
			(end 1.651 1.778)
			(stroke
				(width 0.1524)
				(type default)
			)
			(layer "F.SilkS")
		)
		(fp_line
			(start -1.651 -1.778)
			(end -1.651 1.778)
			(stroke
				(width 0.1524)
				(type default)
			)
			(layer "F.SilkS")
		)
		(fp_poly
			(pts
				(xy -1.778 1.8796) (xy -1.778 -1.8796) (xy 1.778 -1.8796) (xy 1.778 1.8796)
			)
			(stroke
				(width 0)
				(type default)
			)
			(fill no)
			(layer "F.CrtYd")
		)
		(fp_poly
			(pts
				(xy -1.778 1.8796) (xy -1.778 -1.8796) (xy 1.778 -1.8796) (xy 1.778 1.8796)
			)
			(stroke
				(width 0)
				(type default)
			)
			(fill no)
			(layer "F.Fab")
		)
		(pad "D" smd custom
			(at 0 -0.9525 180)
			(size 0.1905 0.1905)
			(layers "F.Cu" "F.Mask" "F.Paste")
			(net "LED_Q_13")
			(options
				(clearance outline)
				(anchor circle)
			)
			(primitives
				(gr_poly
					(pts
						(arc
							(start -0.1778 0.5715)
							(mid -0.321484 0.511984)
							(end -0.381 0.3683)
						)
						(arc
							(start -0.381 -0.3683)
							(mid -0.321484 -0.511984)
							(end -0.1778 -0.5715)
						)
						(arc
							(start 0.1778 -0.5715)
							(mid 0.321484 -0.511984)
							(end 0.381 -0.3683)
						)
						(arc
							(start 0.381 0.3683)
							(mid 0.321484 0.511984)
							(end 0.1778 0.5715)
						)
					)
					(width 0)
					(fill yes)
				)
			)
		)
		(pad "G" smd custom
			(at -0.98425 0.9525 180)
			(size 0.1905 0.1905)
			(layers "F.Cu" "F.Mask" "F.Paste")
			(net "VS5_LED_R")
			(options
				(clearance outline)
				(anchor circle)
			)
			(primitives
				(gr_poly
					(pts
						(arc
							(start -0.1778 0.5715)
							(mid -0.321484 0.511984)
							(end -0.381 0.3683)
						)
						(arc
							(start -0.381 -0.3683)
							(mid -0.321484 -0.511984)
							(end -0.1778 -0.5715)
						)
						(arc
							(start 0.1778 -0.5715)
							(mid 0.321484 -0.511984)
							(end 0.381 -0.3683)
						)
						(arc
							(start 0.381 0.3683)
							(mid 0.321484 0.511984)
							(end 0.1778 0.5715)
						)
					)
					(width 0)
					(fill yes)
				)
			)
		)
		(pad "S" smd custom
			(at 0.98425 0.9525 180)
			(size 0.1905 0.1905)
			(layers "F.Cu" "F.Mask" "F.Paste")
			(net "GND")
			(options
				(clearance outline)
				(anchor circle)
			)
			(primitives
				(gr_poly
					(pts
						(arc
							(start -0.1778 0.5715)
							(mid -0.321484 0.511984)
							(end -0.381 0.3683)
						)
						(arc
							(start -0.381 -0.3683)
							(mid -0.321484 -0.511984)
							(end -0.1778 -0.5715)
						)
						(arc
							(start 0.1778 -0.5715)
							(mid 0.321484 -0.511984)
							(end 0.381 -0.3683)
						)
						(arc
							(start 0.381 0.3683)
							(mid 0.321484 0.511984)
							(end 0.1778 0.5715)
						)
					)
					(width 0)
					(fill yes)
				)
			)
		)
	)
	(footprint ""
		(layer "F.Cu")
		(at 248.7676 -9.0424)
		(property "Reference" "C470"
			(at 0 0 0)
			(layer "F.SilkS")
			(hide yes)
			(effects
				(font
					(size 1.27 1.27)
				)
			)
		)
		(property "Value" "SC4D7U16V5KX-1-GP"
			(at -0.0762 -6.1214 0)
			(unlocked yes)
			(layer "F.Fab")
			(hide yes)
			(effects
				(font
					(size 1.016 1.016)
					(thickness 0.1524)
				)
			)
		)
		(property "Device Type" "C805H56"
			(at -0.0762 -8.1534 0)
			(unlocked yes)
			(layer "F.Fab")
			(hide yes)
			(effects
				(font
					(size 1.016 1.016)
					(thickness 0.1524)
				)
			)
		)
		(duplicate_pad_numbers_are_jumpers no)
		(fp_line
			(start 0.635 0)
			(end -0.635 0)
			(stroke
				(width 0.508)
				(type default)
			)
			(layer "F.SilkS")
		)
		(fp_rect
			(start -0.9652 1.778)
			(end 0.9652 -1.778)
			(stroke
				(width 0)
				(type default)
			)
			(fill no)
			(layer "F.CrtYd")
		)
		(fp_poly
			(pts
				(xy -0.9652 -1.778) (xy 0.9652 -1.778) (xy 0.9652 1.778) (xy -0.9652 1.778)
			)
			(stroke
				(width 0)
				(type default)
			)
			(fill no)
			(layer "F.Fab")
		)
		(pad "1" smd rect
			(at 0 -0.9652)
			(size 1.397 1.143)
			(layers "F.Cu" "F.Mask" "F.Paste")
			(net "DUT_VDDO")
		)
		(pad "2" smd rect
			(at 0 0.9652)
			(size 1.397 1.143)
			(layers "F.Cu" "F.Mask" "F.Paste")
			(net "GND")
		)
	)
	(footprint ""
		(layer "F.Cu")
		(at 7.874 -108.966 90)
		(property "Reference" "PR73"
			(at 0 0 90)
			(layer "F.SilkS")
			(hide yes)
			(effects
				(font
					(size 1.27 1.27)
				)
			)
		)
		(property "Value" "10KR2F-2-GP"
			(at 0.064008 -3.993896 90)
			(unlocked yes)
			(layer "F.Fab")
			(hide yes)
			(effects
				(font
					(size 1.016 1.016)
					(thickness 0.1524)
				)
			)
		)
		(property "Device Type" "R402H16"
			(at 0.064008 -5.517896 90)
			(unlocked yes)
			(layer "F.Fab")
			(hide yes)
			(effects
				(font
					(size 1.016 1.016)
					(thickness 0.1524)
				)
			)
		)
		(duplicate_pad_numbers_are_jumpers no)
		(fp_line
			(start 0.508 -0.9398)
			(end -0.508 -0.9398)
			(stroke
				(width 0.1524)
				(type default)
			)
			(layer "F.SilkS")
		)
		(fp_line
			(start -0.508 -0.9398)
			(end -0.508 0.9398)
			(stroke
				(width 0.1524)
				(type default)
			)
			(layer "F.SilkS")
		)
		(fp_rect
			(start -0.508 0.9398)
			(end 0.508 -0.9398)
			(stroke
				(width 0)
				(type default)
			)
			(fill no)
			(layer "F.CrtYd")
		)
		(fp_rect
			(start -0.508 0.9398)
			(end 0.508 -0.9398)
			(stroke
				(width 0)
				(type default)
			)
			(fill no)
			(layer "F.Fab")
		)
		(pad "1" smd custom
			(at 0 -0.4445 90)
			(size 0.1397 0.1397)
			(layers "F.Cu" "F.Mask" "F.Paste")
			(net "P3V3_STBY")
			(options
				(clearance outline)
				(anchor circle)
			)
			(primitives
				(gr_poly
					(pts
						(arc
							(start -0.1778 -0.2794)
							(mid -0.249642 -0.249642)
							(end -0.2794 -0.1778)
						)
						(arc
							(start -0.2794 0.1778)
							(mid -0.249642 0.249642)
							(end -0.1778 0.2794)
						)
						(arc
							(start 0.1778 0.2794)
							(mid 0.249642 0.249642)
							(end 0.2794 0.1778)
						)
						(arc
							(start 0.2794 -0.1778)
							(mid 0.249642 -0.249642)
							(end 0.1778 -0.2794)
						)
					)
					(width 0)
					(fill yes)
				)
			)
		)
		(pad "2" smd custom
			(at 0 0.4445 90)
			(size 0.1397 0.1397)
			(layers "F.Cu" "F.Mask" "F.Paste")
			(net "PWRGD_P1V26_STBY")
			(options
				(clearance outline)
				(anchor circle)
			)
			(primitives
				(gr_poly
					(pts
						(arc
							(start -0.1778 -0.2794)
							(mid -0.249642 -0.249642)
							(end -0.2794 -0.1778)
						)
						(arc
							(start -0.2794 0.1778)
							(mid -0.249642 0.249642)
							(end -0.1778 0.2794)
						)
						(arc
							(start 0.1778 0.2794)
							(mid 0.249642 0.249642)
							(end 0.2794 0.1778)
						)
						(arc
							(start 0.2794 -0.1778)
							(mid 0.249642 -0.249642)
							(end 0.1778 -0.2794)
						)
					)
					(width 0)
					(fill yes)
				)
			)
		)
	)
	(footprint ""
		(layer "F.Cu")
		(at 150.231602 -53.672232 90)
		(property "Reference" "R13"
			(at 0 0 90)
			(layer "F.SilkS")
			(hide yes)
			(effects
				(font
					(size 1.27 1.27)
				)
			)
		)
		(property "Value" "0R2J-2-GP"
			(at 0.064008 -3.993896 90)
			(unlocked yes)
			(layer "F.Fab")
			(hide yes)
			(effects
				(font
					(size 1.016 1.016)
					(thickness 0.1524)
				)
			)
		)
		(property "Device Type" "R402H16"
			(at 0.064008 -5.517896 90)
			(unlocked yes)
			(layer "F.Fab")
			(hide yes)
			(effects
				(font
					(size 1.016 1.016)
					(thickness 0.1524)
				)
			)
		)
		(duplicate_pad_numbers_are_jumpers no)
		(fp_line
			(start 0.508 -0.9398)
			(end -0.508 -0.9398)
			(stroke
				(width 0.1524)
				(type default)
			)
			(layer "F.SilkS")
		)
		(fp_line
			(start -0.508 -0.9398)
			(end -0.508 0.9398)
			(stroke
				(width 0.1524)
				(type default)
			)
			(layer "F.SilkS")
		)
		(fp_rect
			(start -0.508 0.9398)
			(end 0.508 -0.9398)
			(stroke
				(width 0)
				(type default)
			)
			(fill no)
			(layer "F.CrtYd")
		)
		(fp_rect
			(start -0.508 0.9398)
			(end 0.508 -0.9398)
			(stroke
				(width 0)
				(type default)
			)
			(fill no)
			(layer "F.Fab")
		)
		(pad "1" smd custom
			(at 0 -0.4445 90)
			(size 0.1397 0.1397)
			(layers "F.Cu" "F.Mask" "F.Paste")
			(net "AVS_ENB1_R")
			(options
				(clearance outline)
				(anchor circle)
			)
			(primitives
				(gr_poly
					(pts
						(arc
							(start -0.1778 -0.2794)
							(mid -0.249642 -0.249642)
							(end -0.2794 -0.1778)
						)
						(arc
							(start -0.2794 0.1778)
							(mid -0.249642 0.249642)
							(end -0.1778 0.2794)
						)
						(arc
							(start 0.1778 0.2794)
							(mid 0.249642 0.249642)
							(end 0.2794 0.1778)
						)
						(arc
							(start 0.2794 -0.1778)
							(mid 0.249642 -0.249642)
							(end 0.1778 -0.2794)
						)
					)
					(width 0)
					(fill yes)
				)
			)
		)
		(pad "2" smd custom
			(at 0 0.4445 90)
			(size 0.1397 0.1397)
			(layers "F.Cu" "F.Mask" "F.Paste")
			(net "AVS_ENB")
			(options
				(clearance outline)
				(anchor circle)
			)
			(primitives
				(gr_poly
					(pts
						(arc
							(start -0.1778 -0.2794)
							(mid -0.249642 -0.249642)
							(end -0.2794 -0.1778)
						)
						(arc
							(start -0.2794 0.1778)
							(mid -0.249642 0.249642)
							(end -0.1778 0.2794)
						)
						(arc
							(start 0.1778 0.2794)
							(mid 0.249642 0.249642)
							(end 0.2794 0.1778)
						)
						(arc
							(start 0.2794 -0.1778)
							(mid 0.249642 -0.249642)
							(end 0.1778 -0.2794)
						)
					)
					(width 0)
					(fill yes)
				)
			)
		)
	)
)
